(kicad_pcb
	(version 20260206)
	(generator "pcbnew")
	(generator_version "10.0")
	(general
		(thickness 1.6)
		(legacy_teardrops no)
	)
	(paper "A4")
	(title_block
		(title "04192023_DAF0TMB3IC0_F0TG_MB_C_brd_V02_OCP.brd")
		(comment 1 "Grand Teton / footprints 2257-2262 of 8354")
	)
	(layers
		(0 "F.Cu" signal "TOP")
		(4 "In1.Cu" signal "GND")
		(6 "In2.Cu" signal "IN1")
		(8 "In3.Cu" signal "GND1")
		(10 "In4.Cu" signal "IN2")
		(12 "In5.Cu" signal "GND2")
		(14 "In6.Cu" signal "IN3")
		(16 "In7.Cu" signal "GND3")
		(18 "In8.Cu" signal "VCC")
		(20 "In9.Cu" signal "VCC1")
		(22 "In10.Cu" signal "GND4")
		(24 "In11.Cu" signal "IN4")
		(26 "In12.Cu" signal "GND5")
		(28 "In13.Cu" signal "IN5")
		(30 "In14.Cu" signal "GND6")
		(32 "In15.Cu" signal "IN6")
		(34 "In16.Cu" signal "GND7")
		(2 "B.Cu" signal "BOTTOM")
		(9 "F.Adhes" user "F.Adhesive")
		(11 "B.Adhes" user "B.Adhesive")
		(13 "F.Paste" user "Package Geometry/Pastemask Top")
		(15 "B.Paste" user "Package Geometry/Pastemask Bottom")
		(5 "F.SilkS" user "Ref Des/Silkscreen Top")
		(7 "B.SilkS" user "Ref Des/Silkscreen Bottom")
		(1 "F.Mask" user "Board Geometry/Soldermask Top")
		(3 "B.Mask" user "Board Geometry/Soldermask Bottom")
		(17 "Dwgs.User" user "User.Drawings")
		(19 "Cmts.User" user "User.Comments")
		(21 "Eco1.User" user "User.Eco1")
		(23 "Eco2.User" user "User.Eco2")
		(25 "Edge.Cuts" user "Board Geometry/Outline")
		(27 "Margin" user)
		(31 "F.CrtYd" user "Package Geometry/Place Bound Top")
		(29 "B.CrtYd" user "Package Geometry/Place Bound Bottom")
		(35 "F.Fab" user "Ref Des/Assembly Top")
		(33 "B.Fab" user "Ref Des/Assembly Bottom")
	)
	(footprint ""
		(layer "F.Cu")
		(at 212.471508 5.082794)
		(property "Reference" "J79"
			(at -4.52374 0.838708 90)
			(unlocked yes)
			(layer "F.SilkS")
			(effects
				(font
					(size 0.7874 0.5842)
					(thickness 0.1524)
				)
				(justify left)
			)
		)
		(property "Value" ""
			(at 0 0 0)
			(layer "F.Fab")
			(effects
				(font
					(size 1.27 1.27)
				)
			)
		)
		(duplicate_pad_numbers_are_jumpers no)
		(fp_line
			(start -1.2192 -2.06756)
			(end 1.2192 -2.06756)
			(stroke
				(width 0.1524)
				(type default)
			)
			(layer "F.SilkS")
		)
		(fp_line
			(start -1.2192 2.06756)
			(end -1.2192 -2.06756)
			(stroke
				(width 0.1524)
				(type default)
			)
			(layer "F.SilkS")
		)
		(fp_line
			(start 1.2192 -2.06756)
			(end 1.2192 2.06756)
			(stroke
				(width 0.1524)
				(type default)
			)
			(layer "F.SilkS")
		)
		(fp_line
			(start 1.2192 2.06756)
			(end -1.2192 2.06756)
			(stroke
				(width 0.1524)
				(type default)
			)
			(layer "F.SilkS")
		)
		(pad "" np_thru_hole circle
			(at -2.8829 -1.27 270)
			(size 1.0414 1.0414)
			(drill 1.0414)
			(layers "*.Cu" "*.Mask")
			(clearance 0.381)
			(thermal_gap 0.381)
		)
		(pad "" np_thru_hole circle
			(at -2.8829 1.27 270)
			(size 1.0414 1.0414)
			(drill 1.0414)
			(layers "*.Cu" "*.Mask")
			(clearance 0.381)
			(thermal_gap 0.381)
		)
		(pad "" np_thru_hole circle
			(at 3.4671 -1.27 270)
			(size 1.0414 1.0414)
			(drill 1.0414)
			(layers "*.Cu" "*.Mask")
			(clearance 0.381)
			(thermal_gap 0.381)
		)
		(pad "" np_thru_hole circle
			(at 3.4671 1.27 270)
			(size 1.0414 1.0414)
			(drill 1.0414)
			(layers "*.Cu" "*.Mask")
			(clearance 0.381)
			(thermal_gap 0.381)
		)
		(pad "1" smd rect
			(at 0.8255 -0.249936 270)
			(size 0.3048 0.508)
			(layers "F.Cu" "F.Mask" "F.Paste")
			(net "DELTA_L_85_10INCH_IN3_DP")
		)
		(pad "2" smd rect
			(at 0.8255 0.249936 270)
			(size 0.3048 0.508)
			(layers "F.Cu" "F.Mask" "F.Paste")
			(net "DELTA_L_85_10INCH_IN3_DN")
		)
		(pad "3" smd circle
			(at 0 0)
			(size 0 0)
			(layers "F.Cu" "F.Mask" "F.Paste")
			(net "DELTA_L_GND_1")
		)
		(zone
			(layer "F.Cu")
			(hatch none 0.5)
			(connect_pads
				(clearance 0)
			)
			(min_thickness 0.25)
			(keepout
				(tracks not_allowed)
				(vias allowed)
				(pads allowed)
				(copperpour not_allowed)
				(footprints allowed)
			)
			(placement
				(enabled no)
				(sheetname "")
			)
			(fill
				(thermal_gap 0.5)
				(thermal_bridge_width 0.5)
				(island_removal_mode 0)
			)
			(polygon
				(pts
					(xy 213.589108 4.534154) (xy 213.589108 4.629658) (xy 212.992208 4.629658) (xy 212.992208 5.036058)
					(xy 213.589108 5.036058) (xy 213.589108 5.12953) (xy 212.992208 5.12953) (xy 212.992208 5.53593)
					(xy 213.589108 5.53593) (xy 213.589108 5.631434) (xy 212.890608 5.631434) (xy 212.890608 4.534154)
				)
			)
		)
		(zone
			(layers "F.Cu" "B.Cu" "In1.Cu" "In2.Cu" "In3.Cu" "In4.Cu" "In5.Cu" "In6.Cu"
				"In7.Cu" "In8.Cu" "In9.Cu" "In10.Cu" "In11.Cu" "In12.Cu" "In13.Cu" "In14.Cu"
				"In15.Cu" "In16.Cu"
			)
			(hatch none 0.5)
			(connect_pads
				(clearance 0)
			)
			(min_thickness 0.25)
			(keepout
				(tracks not_allowed)
				(vias allowed)
				(pads allowed)
				(copperpour not_allowed)
				(footprints allowed)
			)
			(placement
				(enabled no)
				(sheetname "")
			)
			(fill
				(thermal_gap 0.5)
				(thermal_bridge_width 0.5)
				(island_removal_mode 0)
			)
			(polygon
				(pts
					(arc
						(start 210.515708 3.812794)
						(mid 208.661508 3.812794)
						(end 210.515708 3.812794)
					)
				)
			)
		)
		(zone
			(layers "F.Cu" "B.Cu" "In1.Cu" "In2.Cu" "In3.Cu" "In4.Cu" "In5.Cu" "In6.Cu"
				"In7.Cu" "In8.Cu" "In9.Cu" "In10.Cu" "In11.Cu" "In12.Cu" "In13.Cu" "In14.Cu"
				"In15.Cu" "In16.Cu"
			)
			(hatch none 0.5)
			(connect_pads
				(clearance 0)
			)
			(min_thickness 0.25)
			(keepout
				(tracks not_allowed)
				(vias allowed)
				(pads allowed)
				(copperpour not_allowed)
				(footprints allowed)
			)
			(placement
				(enabled no)
				(sheetname "")
			)
			(fill
				(thermal_gap 0.5)
				(thermal_bridge_width 0.5)
				(island_removal_mode 0)
			)
			(polygon
				(pts
					(arc
						(start 210.515708 6.352794)
						(mid 208.661508 6.352794)
						(end 210.515708 6.352794)
					)
				)
			)
		)
		(zone
			(layers "F.Cu" "B.Cu" "In1.Cu" "In2.Cu" "In3.Cu" "In4.Cu" "In5.Cu" "In6.Cu"
				"In7.Cu" "In8.Cu" "In9.Cu" "In10.Cu" "In11.Cu" "In12.Cu" "In13.Cu" "In14.Cu"
				"In15.Cu" "In16.Cu"
			)
			(hatch none 0.5)
			(connect_pads
				(clearance 0)
			)
			(min_thickness 0.25)
			(keepout
				(tracks not_allowed)
				(vias allowed)
				(pads allowed)
				(copperpour not_allowed)
				(footprints allowed)
			)
			(placement
				(enabled no)
				(sheetname "")
			)
			(fill
				(thermal_gap 0.5)
				(thermal_bridge_width 0.5)
				(island_removal_mode 0)
			)
			(polygon
				(pts
					(arc
						(start 216.865708 3.812794)
						(mid 215.011508 3.812794)
						(end 216.865708 3.812794)
					)
				)
			)
		)
		(zone
			(layers "F.Cu" "B.Cu" "In1.Cu" "In2.Cu" "In3.Cu" "In4.Cu" "In5.Cu" "In6.Cu"
				"In7.Cu" "In8.Cu" "In9.Cu" "In10.Cu" "In11.Cu" "In12.Cu" "In13.Cu" "In14.Cu"
				"In15.Cu" "In16.Cu"
			)
			(hatch none 0.5)
			(connect_pads
				(clearance 0)
			)
			(min_thickness 0.25)
			(keepout
				(tracks not_allowed)
				(vias allowed)
				(pads allowed)
				(copperpour not_allowed)
				(footprints allowed)
			)
			(placement
				(enabled no)
				(sheetname "")
			)
			(fill
				(thermal_gap 0.5)
				(thermal_bridge_width 0.5)
				(island_removal_mode 0)
			)
			(polygon
				(pts
					(arc
						(start 216.865708 6.352794)
						(mid 215.011508 6.352794)
						(end 216.865708 6.352794)
					)
				)
			)
		)
	)
	(footprint ""
		(layer "F.Cu")
		(at 299.903896 -381.41783 -90)
		(property "Reference" "C928"
			(at 0 0 270)
			(layer "F.SilkS")
			(hide yes)
			(effects
				(font
					(size 1.27 1.27)
				)
			)
		)
		(property "Value" ""
			(at 0 0 270)
			(layer "F.Fab")
			(effects
				(font
					(size 1.27 1.27)
				)
			)
		)
		(duplicate_pad_numbers_are_jumpers no)
		(fp_line
			(start -0.299974 0.150114)
			(end -0.299974 -0.150114)
			(stroke
				(width 0.1)
				(type default)
			)
			(layer "F.Fab")
		)
		(fp_line
			(start 0.299974 0.150114)
			(end -0.299974 0.150114)
			(stroke
				(width 0.1)
				(type default)
			)
			(layer "F.Fab")
		)
		(fp_line
			(start -0.299974 -0.150114)
			(end 0.299974 -0.150114)
			(stroke
				(width 0.1)
				(type default)
			)
			(layer "F.Fab")
		)
		(fp_line
			(start 0.299974 -0.150114)
			(end 0.299974 0.150114)
			(stroke
				(width 0.1)
				(type default)
			)
			(layer "F.Fab")
		)
		(pad "1" smd rect
			(at -0.2667 0 270)
			(size 0.3048 0.381)
			(layers "F.Cu" "F.Mask" "F.Paste")
			(net "P5E_CPU0_P0_TX_C_DN<2>")
		)
		(pad "2" smd rect
			(at 0.2667 0 270)
			(size 0.3048 0.381)
			(layers "F.Cu" "F.Mask" "F.Paste")
			(net "P5E_CPU0_P0_TX_DN<2>")
		)
	)
	(footprint ""
		(layer "F.Cu")
		(at 58.191654 -346.719398 -90)
		(property "Reference" "PC401_C1P1_4"
			(at 0 0 270)
			(layer "F.SilkS")
			(hide yes)
			(effects
				(font
					(size 1.27 1.27)
				)
			)
		)
		(property "Value" ""
			(at 0 0 270)
			(layer "F.Fab")
			(effects
				(font
					(size 1.27 1.27)
				)
			)
		)
		(duplicate_pad_numbers_are_jumpers no)
		(fp_line
			(start -0.7874 0.4064)
			(end -0.7874 -0.4064)
			(stroke
				(width 0.1524)
				(type default)
			)
			(layer "F.SilkS")
		)
		(fp_line
			(start 0.7874 0.4064)
			(end -0.7874 0.4064)
			(stroke
				(width 0.1524)
				(type default)
			)
			(layer "F.SilkS")
		)
		(fp_line
			(start -0.7874 -0.4064)
			(end 0.7874 -0.4064)
			(stroke
				(width 0.1524)
				(type default)
			)
			(layer "F.SilkS")
		)
		(fp_line
			(start 0.7874 -0.4064)
			(end 0.7874 0.4064)
			(stroke
				(width 0.1524)
				(type default)
			)
			(layer "F.SilkS")
		)
		(fp_line
			(start -0.67945 0.3048)
			(end -0.67945 -0.305054)
			(stroke
				(width 0.1)
				(type default)
			)
			(layer "F.Fab")
		)
		(fp_line
			(start -0.12065 0.3048)
			(end -0.67945 0.3048)
			(stroke
				(width 0.1)
				(type default)
			)
			(layer "F.Fab")
		)
		(fp_line
			(start 0.120396 0.3048)
			(end 0.120396 0.2794)
			(stroke
				(width 0.1)
				(type default)
			)
			(layer "F.Fab")
		)
		(fp_line
			(start 0.67945 0.3048)
			(end 0.120396 0.3048)
			(stroke
				(width 0.1)
				(type default)
			)
			(layer "F.Fab")
		)
		(fp_line
			(start -0.12065 0.2794)
			(end -0.12065 0.3048)
			(stroke
				(width 0.1)
				(type default)
			)
			(layer "F.Fab")
		)
		(fp_line
			(start 0.120396 0.2794)
			(end -0.12065 0.2794)
			(stroke
				(width 0.1)
				(type default)
			)
			(layer "F.Fab")
		)
		(fp_line
			(start -0.12065 -0.2794)
			(end 0.12065 -0.2794)
			(stroke
				(width 0.1)
				(type default)
			)
			(layer "F.Fab")
		)
		(fp_line
			(start 0.12065 -0.2794)
			(end 0.12065 -0.3048)
			(stroke
				(width 0.1)
				(type default)
			)
			(layer "F.Fab")
		)
		(fp_line
			(start 0.12065 -0.3048)
			(end 0.67945 -0.3048)
			(stroke
				(width 0.1)
				(type default)
			)
			(layer "F.Fab")
		)
		(fp_line
			(start 0.67945 -0.3048)
			(end 0.67945 0.3048)
			(stroke
				(width 0.1)
				(type default)
			)
			(layer "F.Fab")
		)
		(fp_line
			(start -0.67945 -0.305054)
			(end -0.12065 -0.305054)
			(stroke
				(width 0.1)
				(type default)
			)
			(layer "F.Fab")
		)
		(fp_line
			(start -0.12065 -0.305054)
			(end -0.12065 -0.2794)
			(stroke
				(width 0.1)
				(type default)
			)
			(layer "F.Fab")
		)
		(pad "1" smd circle
			(at -0.40005 0 270)
			(size 0 0)
			(layers "F.Cu" "F.Mask" "F.Paste")
			(net "PVDDCR_CPU1_P1_PVCC")
		)
		(pad "2" smd circle
			(at 0.40005 0 270)
			(size 0 0)
			(layers "F.Cu" "F.Mask" "F.Paste")
			(net "GND")
		)
	)
	(footprint ""
		(layer "F.Cu")
		(at 150.502366 -56.204358)
		(property "Reference" "R3611"
			(at 0 0 0)
			(layer "F.SilkS")
			(hide yes)
			(effects
				(font
					(size 1.27 1.27)
				)
			)
		)
		(property "Value" ""
			(at 0 0 0)
			(layer "F.Fab")
			(effects
				(font
					(size 1.27 1.27)
				)
			)
		)
		(duplicate_pad_numbers_are_jumpers no)
		(fp_line
			(start -0.7874 -0.4064)
			(end 0.7874 -0.4064)
			(stroke
				(width 0.1524)
				(type default)
			)
			(layer "F.SilkS")
		)
		(fp_line
			(start -0.7874 0.4064)
			(end -0.7874 -0.4064)
			(stroke
				(width 0.1524)
				(type default)
			)
			(layer "F.SilkS")
		)
		(fp_line
			(start 0.7874 -0.4064)
			(end 0.7874 0.4064)
			(stroke
				(width 0.1524)
				(type default)
			)
			(layer "F.SilkS")
		)
		(fp_line
			(start 0.7874 0.4064)
			(end -0.7874 0.4064)
			(stroke
				(width 0.1524)
				(type default)
			)
			(layer "F.SilkS")
		)
		(fp_line
			(start -0.67945 -0.305054)
			(end -0.12065 -0.305054)
			(stroke
				(width 0.1)
				(type default)
			)
			(layer "F.Fab")
		)
		(fp_line
			(start -0.67945 0.3048)
			(end -0.67945 -0.305054)
			(stroke
				(width 0.1)
				(type default)
			)
			(layer "F.Fab")
		)
		(fp_line
			(start -0.12065 -0.305054)
			(end -0.12065 -0.2794)
			(stroke
				(width 0.1)
				(type default)
			)
			(layer "F.Fab")
		)
		(fp_line
			(start -0.12065 -0.2794)
			(end 0.12065 -0.2794)
			(stroke
				(width 0.1)
				(type default)
			)
			(layer "F.Fab")
		)
		(fp_line
			(start -0.12065 0.2794)
			(end -0.12065 0.3048)
			(stroke
				(width 0.1)
				(type default)
			)
			(layer "F.Fab")
		)
		(fp_line
			(start -0.12065 0.3048)
			(end -0.67945 0.3048)
			(stroke
				(width 0.1)
				(type default)
			)
			(layer "F.Fab")
		)
		(fp_line
			(start 0.120396 0.2794)
			(end -0.12065 0.2794)
			(stroke
				(width 0.1)
				(type default)
			)
			(layer "F.Fab")
		)
		(fp_line
			(start 0.120396 0.3048)
			(end 0.120396 0.2794)
			(stroke
				(width 0.1)
				(type default)
			)
			(layer "F.Fab")
		)
		(fp_line
			(start 0.12065 -0.3048)
			(end 0.67945 -0.3048)
			(stroke
				(width 0.1)
				(type default)
			)
			(layer "F.Fab")
		)
		(fp_line
			(start 0.12065 -0.2794)
			(end 0.12065 -0.3048)
			(stroke
				(width 0.1)
				(type default)
			)
			(layer "F.Fab")
		)
		(fp_line
			(start 0.67945 -0.3048)
			(end 0.67945 0.3048)
			(stroke
				(width 0.1)
				(type default)
			)
			(layer "F.Fab")
		)
		(fp_line
			(start 0.67945 0.3048)
			(end 0.120396 0.3048)
			(stroke
				(width 0.1)
				(type default)
			)
			(layer "F.Fab")
		)
		(pad "1" smd circle
			(at -0.40005 0)
			(size 0 0)
			(layers "F.Cu" "F.Mask" "F.Paste")
			(net "GND")
		)
		(pad "2" smd circle
			(at 0.40005 0)
			(size 0 0)
			(layers "F.Cu" "F.Mask" "F.Paste")
			(net "INA230_4_A0")
		)
	)
	(footprint ""
		(layer "F.Cu")
		(at 174.635922 -25.846532 180)
		(property "Reference" "PC2239"
			(at 0 0 180)
			(layer "F.SilkS")
			(hide yes)
			(effects
				(font
					(size 1.27 1.27)
				)
			)
		)
		(property "Value" ""
			(at 0 0 180)
			(layer "F.Fab")
			(effects
				(font
					(size 1.27 1.27)
				)
			)
		)
		(duplicate_pad_numbers_are_jumpers no)
		(fp_line
			(start 1.2954 0.5842)
			(end -1.2954 0.5842)
			(stroke
				(width 0.1524)
				(type default)
			)
			(layer "F.SilkS")
		)
		(fp_line
			(start 1.2954 -0.5842)
			(end 1.2954 0.5842)
			(stroke
				(width 0.1524)
				(type default)
			)
			(layer "F.SilkS")
		)
		(fp_line
			(start -1.2954 0.5842)
			(end -1.2954 -0.5842)
			(stroke
				(width 0.1524)
				(type default)
			)
			(layer "F.SilkS")
		)
		(fp_line
			(start -1.2954 -0.5842)
			(end 1.2954 -0.5842)
			(stroke
				(width 0.1524)
				(type default)
			)
			(layer "F.SilkS")
		)
		(fp_line
			(start 1.1938 0.4064)
			(end 0.8636 0.4064)
			(stroke
				(width 0.1)
				(type default)
			)
			(layer "F.Fab")
		)
		(fp_line
			(start 1.1938 -0.4064)
			(end 1.1938 0.4064)
			(stroke
				(width 0.1)
				(type default)
			)
			(layer "F.Fab")
		)
		(fp_line
			(start 0.8636 0.4572)
			(end -0.8636 0.4572)
			(stroke
				(width 0.1)
				(type default)
			)
			(layer "F.Fab")
		)
		(fp_line
			(start 0.8636 0.4064)
			(end 0.8636 0.4572)
			(stroke
				(width 0.1)
				(type default)
			)
			(layer "F.Fab")
		)
		(fp_line
			(start 0.8636 -0.4064)
			(end 1.1938 -0.4064)
			(stroke
				(width 0.1)
				(type default)
			)
			(layer "F.Fab")
		)
		(fp_line
			(start 0.8636 -0.4572)
			(end 0.8636 -0.4064)
			(stroke
				(width 0.1)
				(type default)
			)
			(layer "F.Fab")
		)
		(fp_line
			(start -0.8636 0.4572)
			(end -0.8636 0.4064)
			(stroke
				(width 0.1)
				(type default)
			)
			(layer "F.Fab")
		)
		(fp_line
			(start -0.8636 0.4064)
			(end -1.1938 0.4064)
			(stroke
				(width 0.1)
				(type default)
			)
			(layer "F.Fab")
		)
		(fp_line
			(start -0.8636 -0.4064)
			(end -0.8636 -0.4572)
			(stroke
				(width 0.1)
				(type default)
			)
			(layer "F.Fab")
		)
		(fp_line
			(start -0.8636 -0.4572)
			(end 0.8636 -0.4572)
			(stroke
				(width 0.1)
				(type default)
			)
			(layer "F.Fab")
		)
		(fp_line
			(start -1.1938 0.4064)
			(end -1.1938 -0.4064)
			(stroke
				(width 0.1)
				(type default)
			)
			(layer "F.Fab")
		)
		(fp_line
			(start -1.1938 -0.4064)
			(end -0.8636 -0.4064)
			(stroke
				(width 0.1)
				(type default)
			)
			(layer "F.Fab")
		)
		(pad "1" smd rect
			(at -0.7366 0 90)
			(size 0.7112 0.8128)
			(layers "F.Cu" "F.Mask" "F.Paste")
			(net "P12V_SCM_AVIN_PD")
		)
		(pad "2" smd rect
			(at 0.7366 0 90)
			(size 0.7112 0.8128)
			(layers "F.Cu" "F.Mask" "F.Paste")
			(net "GND")
		)
	)
	(footprint ""
		(layer "F.Cu")
		(at 360.40949 -395.1732 90)
		(property "Reference" "R1014"
			(at 0 0 90)
			(layer "F.SilkS")
			(hide yes)
			(effects
				(font
					(size 1.27 1.27)
				)
			)
		)
		(property "Value" ""
			(at 0 0 90)
			(layer "F.Fab")
			(effects
				(font
					(size 1.27 1.27)
				)
			)
		)
		(duplicate_pad_numbers_are_jumpers no)
		(fp_line
			(start 0.32512 -0.175006)
			(end 0.32512 0.175006)
			(stroke
				(width 0.1)
				(type default)
			)
			(layer "F.Fab")
		)
		(fp_line
			(start -0.32512 -0.175006)
			(end 0.32512 -0.175006)
			(stroke
				(width 0.1)
				(type default)
			)
			(layer "F.Fab")
		)
		(fp_line
			(start 0.32512 0.175006)
			(end -0.32512 0.175006)
			(stroke
				(width 0.1)
				(type default)
			)
			(layer "F.Fab")
		)
		(fp_line
			(start -0.32512 0.175006)
			(end -0.32512 -0.175006)
			(stroke
				(width 0.1)
				(type default)
			)
			(layer "F.Fab")
		)
		(pad "1" smd rect
			(at -0.2667 0 90)
			(size 0.3048 0.381)
			(layers "F.Cu" "F.Mask" "F.Paste")
			(net "RT_CPU0_P1_ADDR3")
		)
		(pad "2" smd rect
			(at 0.2667 0 270)
			(size 0.3048 0.381)
			(layers "F.Cu" "F.Mask" "F.Paste")
			(net "GND")
		)
	)
)
